# Bryce Canyon_IOM_M2_Stackup.xlsx — PCB Test Plan_HVM(90+) (pcb-stackup)
|  | Board vendor give feedback of quantity in yellow columns based on the AQL table or description. |  |  |  |  |  |  |  |  |  |  |  |  |  |  |
|  | Wiwynn PM give feedback in blue columns |  |  |  |  |  |  |  |  |  |  |  |  |  |  |
| Person to be informed : PCB vendor, EE, SI, PM, PSM, Buyer, SQM |  |  |  |  |  |  |  |  |  |  |  |  |  |  |  |
| Simple flow : SI (test requirements) -> PM/AM (Total PCBS demand) -> Buyer -> Board Vendor (yellow column feedback) -> Buyer -> Person to be informed (Check and Track) |  |  |  |  |  |  |  |  |  |  |  |  |  |  |  |
| PO(purchase order) : If there are many POs for this PCB, 1st sample quantity is based on 1st PO, 2nd sample quantity is based on 2nd PO. |  |  |  |  |  |  |  |  |  |  |  |  |  |  |  |
| Project Name | PCB name | PCB# (1XXXX-XX) | Product Stage | Batch# | PCB Vendor | Production  Lot size | PCBs Demand | Delta-L Coupon (PCB Vendor) | Delta-L Coupon (3rd Party Lab) | Impedance Coupon (PCB Vendor) | In-board trace correlation (PCB Vendor) | X-section Analysis (PCB Vendor) | IST (3rd Party Lab) | IPC-6012D (3rd Party Lab) | Note |
| Bryce Canyon | IOM M2 | 16342-2 | HVM(90+ days) | N/A |  |  | TBD | No | No | Yes | No | No | No | No | Need Test? (Yes, No) |
| Tracking Code On Both Of Coupon And PCB |  |  |  |  |  |  |  |  |  | N/A |  |  |  |  |  |
| Test Item Acceptance Criteria |  |  |  |  |  |  |  |  |  | c = 0 |  |  |  |  |  |
| Test Item Sampling Quantity |  |  |  |  |  |  |  |  |  | Mil-STD 105E single sampling plan, AQL 0.65, level 2 |  |  |  |  |  |
| Test Time (working days) |  |  |  |  |  |  |  |  |  |  |  |  |  |  |  |
| Test Item Shipping Quantity |  |  |  |  |  |  |  |  |  |  |  |  |  |  |  |
| Shipping Address |  |  |  |  |  |  |  |  |  |  |  |  |  |  |  |
| Receiver Name |  |  |  |  |  |  |  |  |  |  |  |  |  |  |  |
| Receiver Phone# |  |  |  |  |  |  |  |  |  |  |  |  |  |  |  |
